# Bryce Canyon_ME BOM MP.xlsx — ME BOM (bom)
| Bryce Canyon ME BOM |  |  |  |  |  |  |  |  |  |  |  |  |  |  |  |  |  |  |  |
|  |  | 料號顏色區分: 藍色  初始料號 紅色  更變料號 黑色  沿用料號 |  |  |  |  |  |  |  |  |  |  |  |  |  |  |  |  |  |
|  | Level | WW P/N EVT | WW P/N DVT | WW P/N DVT2 | WW P/N MP | Description (PDM) | Part Name | Picture | Tool status | Type 7 JBOD Usage/ Lower level | Type 7 JBOD Usage/ System | Type 5 Usage/ Lower level | Type 5 Usage/ System | Type 7  Usage/ Lower level | Type 7  Usage/ System | Material/Finish | Type: Assy/Metal/Plastic/Purchase/Cable | Suppier | Remark |
|  | 1 | B60.01108.0001 | B60.0110T.0001 | B60.0110T.0011 | B60.0110T.0021 | ASSY MAIN CHASSIS TYPE4/7 JBOD BC MP | 00-ACKBAR TOP ASSEMBLY |  |  | 1 | 1 |  |  |  |  |  |  |  |  |
|  |  |  |  |  |  | ASSY |  |  |  |  |  |  |  |  |  |  |  |  |  |
|  |  |  |  |  |  | Packing |  |  |  |  |  |  |  |  |  |  |  |  |  |
|  |  |  |  |  |  | Transportation |  |  |  |  |  |  |  |  |  |  |  |  |  |
|  | 1 | B60.01101.0001 | B60.0110S.0001 | B60.0110S.0011 | B60.0110S.0021 | ASSY MAIN CHASSIS TYPE5 BC MP | 00-ACKBAR TOP ASSEMBLY |  |  |  |  | 1 | 1 |  |  |  |  |  |  |
|  |  |  |  |  |  | ASSY |  |  |  |  |  |  |  |  |  |  |  |  |  |
|  |  |  |  |  |  | Packing |  |  |  |  |  |  |  |  |  |  |  |  |  |
|  |  |  |  |  |  | Transportation |  |  |  |  |  |  |  |  |  |  |  |  |  |
|  | 1 | B60.01109.0001 | B60.0110U.0001 | B60.0110U.0011 | B60.0110U.0021 | ASSY MAIN CHASSIS TYPE7 HEADNODE BC MP | 00-ACKBAR TOP ASSEMBLY |  |  |  |  |  |  | 1 | 1 |  |  |  |  |
|  |  |  |  |  |  | ASSY |  |  |  |  |  |  |  |  |  |  |  |  |  |
|  |  |  |  |  |  | Packing |  |  |  |  |  |  |  |  |  |  |  |  |  |
|  |  |  |  |  |  | Transportation |  |  |  |  |  |  |  |  |  |  |  |  |  |
|  | 2 | B60.01104.0001 | B60.01104.0001 | B60.01104.0001 | B60.01104.0001 | ASSY MAIN HOUSING BRCA | 01-ASSY LOW CASE ACKBAR |  |  | 1 | 1 | 1 | 1 | 1 | 1 | Assy | Assy |  |  |
|  | 3 | B34.01101.0001 | B34.01101.0001 | B34.01101.0001 | B34.01101.0001 | CVR LOW CASE TOP COVER BRCA | 03-FRONT TOP COVER BRYCE CANYON_DVT |  | PVT new tool | 1 | 1 | 1 | 1 | 1 | 1 | SGCC(T=1.2mm)/NA | Metal | 長江 | M1 |
|  | 3 |  |  |  |  | CAS LOW CASE TRITON | 02-ASSY LOW CASE TRITON |  |  | 1 | 1 | 1 | 1 | 1 | 1 | Assy | Assy |  |  |
|  | 4 | B30.01101.0001 | B30.01101.0001 | B30.01101.0001 | B30.01101.0001 | CAS LOW CASE BRCA | 03-LOW CASE BRYCE CANYON_DVT |  |  | 1 | 1 | 1 | 1 | 1 | 1 | Assy | Assy |  |  |
|  | 5 |  |  |  |  |  | 03-LOW_CASE_BRYCE_CANYON_DVT |  | PVT new tool | 1 | 1 | 1 | 1 | 1 | 1 | SGCC(T=1.2mm)/NA | Metal | 長江 | M2 |
|  | 5 |  |  |  |  |  | STD  LOW CASE-2 TRITON_DVT |  |  | 4 | 4 | 4 | 4 | 4 | 4 | Standoff | Purchase | 長江 |  |
|  | 5 |  |  |  |  |  |  |  |  | 6 | 6 | 6 | 6 | 6 | 6 | Verdor PN:E2017-192 | Purchase | Fivetech |  |
|  | 4 | B34.01103.0001 | B34.01103.0001 | B34.01103.0001 | B34.01103.0001 | LATCH LOW CASE BRCA | FRONT_LATCH_CUBBY_E1_CA_DVT |  | PVT new tool | 2 | 2 | 2 | 2 | 2 | 2 | Stainsteel T=2.0mm/NA | Metal | 長江 | M3 |
|  | 3 | B33.0110J.0001 | B33.0110J.0001 | B33.0110J.0001 | B33.0110J.0001 | HLDR CABLE TRACK LOW CASE BRCA | 02-CABLE TRACK HOLDER LOW CASE TRITON |  | PVT new tool | 1 | 1 | 1 | 1 | 1 | 1 | SGCC(T=0.8mm)/NA | Metal | 長江 | M4 |
|  | 3 |  | B33.01114.0001 | B33.01114.0001 | B33.01114.0001 | BRKT REMOVABLE BACKDOOR BRCA | ASSY REMOVABLE BKT BACK DOOR |  |  | 1 | 1 | 1 | 1 | 1 | 1 | Assy | Assy |  |  |
|  | 4 |  |  |  |  |  | REMOVABLE BKT BACK DOOR |  | PVT new tool | 1 | 1 | 1 | 1 | 1 | 1 | SGCC(T=1.0mm)/NA | Metal | 長江 | M27 |
|  | 4 |  |  |  |  |  | STD_BACK DOOR |  |  | 2 | 2 | 2 | 2 | 2 | 2 | Standoff | Purchase | 長江 |  |
|  | 3 | B33.0110N.0001 | B33.0110N.0001 | B33.0110N.0001 | B33.0110N.0001 | SENSOR SWITCH BRACKET BRCA | 03-SENSOR SWITCH BRACKET BRYCE CANYON_DVT |  | PVT new tool | 1 | 1 | 1 | 1 | 1 | 1 | SGCC(T=1.6mm)/NA | Metal | 長江 | M5 |
|  | 3 | B34.01105.0001 | B34.01105.0001 | B34.01105.0001 | B34.01105.0001 | HANDLE LOW CASE | HANDLE LOW CASE(71-14707-5) |  |  | 4 | 4 | 4 | 4 | 4 | 4 | Verdor PN:71-14707-5 | Purchase | Fivetech |  |
|  | 3 | B47.0111X.0001 | B47.0111X.0001 | B47.0111X.0001 | B47.0111X.0001 | MYLAR FRONT TOP COVER TRITON | MYLAR FRONT TOP COVER |  |  | 2 | 2 | 2 | 2 | 2 | 2 | Mylar | Purchase | 德竹 |  |
|  | 3 | B47.0110W.0001 | B47.0110W.0001 | B47.0110W.0001 | B47.0110W.0001 | LOW CASE TRITON (SPONGE) | LOW CASE DPB SEAL SPONGE |  |  | 1 | 1 | 1 | 1 | 1 | 1 | Sponge(E4382) | Purchase | 德竹 |  |
|  | 3 | B47.0111L.0001 | B47.0111L.0001 | B47.0111L.0001 | B47.0111L.0001 | SPONGE IOM SUPER CAP SUPPORT | IOM SUPER CAP SUPPORT SPONGE |  |  | 2 | 2 | 2 | 2 | 2 | 2 | Sponge(E4382) | Purchase | 德竹 |  |
|  | 3 |  | B34.0110X.0001 | B34.0110X.0001 | B34.0110X.0001 | EMI GASKET LOWCASE REAR INNER BC DVT | LOW CASE FAN TRAY INSIDE GASKET |  |  | 2 | 2 | 2 | 2 | 2 | 2 | Gasket | Purchase | 德竹 |  |
|  | 3 |  | B34.0110Y.0001 | B34.0110Y.0001 | B34.0110Y.0001 | EMI GASKET LOWCASE REAR OUTER BC DVT | LOW CASE FAN TRAY OUTSIDE GASKET |  |  | 2 | 2 | 2 | 2 | 2 | 2 | Gasket | Purchase | 德竹 |  |
|  | 3 |  | B34.0110Z.0001 | B34.0110Z.0001 | B34.0110Z.0001 | EMI GASKET LOWCASE REAR BOT BC DVT | LOW CASE FAN TRAY BOTTOM GASKET |  |  | 2 | 2 | 2 | 2 | 2 | 2 | Gasket | Purchase | 德竹 |  |
|  | 3 |  |  | B34.01117.0001 | B34.01117.0001 | EMI GASKET LOWCASE FRONT BC | LOW CASE FRONT GASKET |  |  | 1 | 1 | 1 | 1 | 1 | 1 | Gasket | Purchase | 德竹 |  |
|  | 3 |  | B47.0112R.0001 | B47.0112R.0001 | B47.0112R.0001 | SPONGE LOWCASE REAR FAN CAGE BC DVT | LOW CASE REAR SIDE FAN SPONGE |  |  | 2 | 2 | 2 | 2 | 2 | 2 | Gasket | Purchase | 德竹 |  |
|  | 3 | 086.1A528.06R0 | 086.1A528.06R0 | 086.1A528.06R0 | 086.1A528.06R0 | SCRW PAN M5X0.8 L6 NI NYLOK | SCREW_086.1A528.06R0 |  |  | 16 | 16 | 16 | 16 | 16 | 16 | Screw | Purchase | 文豪 | uses: 16 for handle low case |
|  | 3 | 86.5A534.4R0 | 86.00R06.644 | 86.00R06.644 | 86.00R06.644 | SCRW FLAT M3*L4 NYLOK | SCREW_86.00R06.644 |  |  | 9 | 9 | 9 | 9 | 9 | 9 | Screw | Purchase | 文豪 | uses: 3 for removable BKT to bus bar holder 2 for removable BKT to low case 4 for top-front CVR |
|  | 2 |  |  | B60.0110X.0001 | B60.0110X.0001 | ASSY DRAWER U6 SLIDE BC DVT2 | DRAWER SLIDER SET TRITON |  |  | 1 | 1 | 1 | 1 | 1 | 1 |  |  | King slide |  |
|  | 2 | B60.01105.0001 | B60.01105.0001 | B60.01105.0011 | B60.01105.0011 | ASSY DRAWER BRCA | 01-ASSY DRAWER ACKBAR |  |  | 1 | 1 | 1 | 1 | 1 | 1 | Assy | Assy |  |  |
|  | 3 | B33.01108.0001 | B33.01108.0001 | B33.01108.0001 | B33.01108.0001 | BRKT DRAWER FRONT BRCA | 02-DRAWER FRONT TRITON |  |  | 1 | 1 | 1 | 1 | 1 | 1 | Assy | Assy |  |  |
|  | 4 |  |  |  |  |  | 03-DRAWER FRONT TRITON |  | PVT new tool | 1 | 1 | 1 | 1 | 1 | 1 | SGCC(T=1.6mm)/NA | Metal | 長江 | M6 |
|  | 4 |  |  |  |  |  | STD_FRONT PANEL 1 TRITON |  |  | 2 | 2 | 2 | 2 | 2 | 2 | Standoff | Purchase | 長江 |  |
|  | 4 |  |  |  |  |  | THUMB SCREW(27-111-201-5) |  |  | 2 | 2 | 2 | 2 | 2 | 2 | Thumb screw | Purchase | Fivetech |  |
|  | 3 | B34.0110A.0001 | B34.0110A.0001 | B34.0110A.0001 | B34.0110A.0001 | BRKT DRAWER FRONT WINDOW BRCA | 02-ASSY VENTING BKT TRITON |  |  | 1 | 1 | 1 | 1 | 1 | 1 | Assy | Assy |  |  |
|  | 4 |  |  |  |  |  | 03-VENTING BKT TRITON TRITON |  | PVT new tool | 1 | 1 | 1 | 1 | 1 | 1 | SGCC(T=1.0mm)/NA | Metal | 長江 | M7 |
|  | 4 |  |  |  |  |  | Right angle plunger (89-1301-499) |  |  | 1 | 1 | 1 | 1 | 1 | 1 | Plunger | Purchase | Fivetech |  |
|  | 3 | B33.0110O.0001 | B33.0110O.0001 | B33.0110O.0001 | B33.0110O.0001 | BRKT DRAWER LEFT SIDE WALL BRCA | 02-DRAWER WALL L TRITON |  |  | 1 | 1 | 1 | 1 | 1 | 1 | Assy | Assy |  |  |
|  | 4 |  |  |  |  |  | 03-DRAWER WALL L TRITON |  | PVT new tool | 1 | 1 | 1 | 1 | 1 | 1 | SGCC(T=1.6mm)/NA | Metal | 長江 | M8 |
|  | 4 |  |  |  |  |  | SIDE WALL PIN |  |  | 7 | 7 | 7 | 7 | 7 | 7 | Standoff | Purchase | 長江 |  |
|  | 4 |  |  |  |  |  | DRAWER SIDE WALL PIN |  |  | 2 | 2 | 2 | 2 | 2 | 2 | Standoff | Purchase | 長江 |  |
|  | 4 |  |  |  |  |  | SO_RAIL_DRAWER_1 |  |  | 2 | 2 | 2 | 2 | 2 | 2 | Standoff | Purchase | 長江 |  |
|  | 3 | B33.0110X.0001 | B33.0110X.0001 | B33.0110X.0001 | B33.0110X.0001 | BRKT DRAWER RIGHT SIDE WALL BRCA | 02-DRAWER WALL R TRITON |  |  | 1 | 1 | 1 | 1 | 1 | 1 | Assy | Assy |  |  |
|  | 4 |  |  |  |  |  | 03-DRAWER WALL R TRITON |  | PVT new tool | 1 | 1 | 1 | 1 | 1 | 1 | SGCC(T=1.6mm)/NA | Metal | 長江 | M9 |
|  | 4 |  |  |  |  |  | SIDE WALL PIN |  |  | 7 | 7 | 7 | 7 | 7 | 7 | Standoff | Purchase | 長江 |  |
|  | 4 |  |  |  |  |  | DRAWER SIDE WALL PIN |  |  | 2 | 2 | 2 | 2 | 2 | 2 | Standoff | Purchase | 長江 |  |
|  | 4 |  |  |  |  |  | SO_RAIL_DRAWER_1 |  |  | 2 | 2 | 2 | 2 | 2 | 2 | Standoff | Purchase | 長江 |  |
|  | 3 | B33.0110F.0001 | B33.0110F.0001 | B33.0110F.0001 | B33.0110F.0001 | BRKT DRAWER REAR WALL BRCA | 02-DRAWER WALL REAR  TRITON |  | PVT new tool | 1 | 1 | 1 | 1 | 1 | 1 | SGCC(T=1.6mm)/NA | Metal | 長江 | M10 |
|  | 3 | B33.0110P.0001 | B33.0110P.0001 | B33.0110P.0001 | B33.0110P.0001 | BRKT COLUMN PARTITION-2 BRCA | 02-COLUMN PARTITION-2  TRITON |  |  | 1 | 1 | 1 | 1 | 1 | 1 | Assy | Assy |  |  |
|  | 4 |  |  |  |  |  | 03-COLUMN PARTITION-2 TRITON |  | PVT new tool | 1 | 1 | 1 | 1 | 1 | 1 | SGCC(T=1.6mm)/NA | Metal | 長江 | M11 |
|  | 4 |  |  |  |  |  | STD_COLUMN PARTITION-1 |  |  | 2 | 2 | 2 | 2 | 2 | 2 | Standoff | Purchase | 長江 |  |
|  | 4 |  |  |  |  |  | MIDDLE WALL PIN |  |  | 4 | 4 | 4 | 4 | 4 | 4 | Standoff | Purchase | 長江 |  |
|  | 4 |  |  |  |  |  | STD_COLUMN PARTITION TRITON |  |  | 4 | 4 | 4 | 4 | 4 | 4 | Standoff | Purchase | 長江 |  |
|  | 4 |  |  |  |  |  | SIDE WALL PIN__0825_0828 |  |  | 7 | 7 | 7 | 7 | 7 | 7 | Standoff | Purchase | 長江 |  |
|  | 4 |  |  |  |  |  | STD_COLUMN PARTITION-2 TRITON_BSO-M3-6-ZI-Colly |  |  | 4 | 4 | 4 | 4 | 4 | 4 | Standoff | Purchase | 長江 |  |
|  | 3 | B33.0110W.0001 | B33.0110W.0001 | B33.0110W.0001 | B33.0110W.0001 | BRKT COLUMN PARTITION-3 BRCA | 02-COLUMN PARTITION-3  TRITON |  |  | 1 | 1 | 1 | 1 | 1 | 1 | Assy | Assy |  |  |
|  | 4 |  |  |  |  |  | 03-COLUMN PARTITION-3  TRITON |  | PVT new tool | 1 | 1 | 1 | 1 | 1 | 1 | SGCC(T=1.6mm)/NA | Metal | 長江 | M12 |
|  | 4 |  |  |  |  |  | STD_COLUMN PARTITION-1 |  |  | 2 | 2 | 2 | 2 | 2 | 2 | Standoff | Purchase | 長江 |  |
|  | 4 |  |  |  |  |  | MIDDLE WALL PIN |  |  | 12 | 12 | 12 | 12 | 12 | 12 | Standoff | Purchase | 長江 |  |
|  | 4 |  |  |  |  |  | SIDE WALL PIN__0825_0828 |  |  | 7 | 7 | 7 | 7 | 7 | 7 | Standoff | Purchase | 長江 |  |
|  | 4 |  |  |  |  |  | STD_COLUMN PARTITION-2 TRITON_BSO-M3-6-ZI-Colly |  |  | 5 | 5 | 5 | 5 | 5 | 5 | Standoff | Purchase | 長江 |  |
|  | 3 | B33.01106.0001 | B33.01106.0001 | B33.01106.0001 | B33.01106.0001 | BRKT COLUMN PARTITION-4 BRCA | 03-COLUMN PARTITION-4 TRITON |  |  | 1 | 1 | 1 | 1 | 1 | 1 | Assy | Assy |  |  |
|  | 4 |  |  |  |  |  | 04-COLUMN PARTITION-4  TRITON |  | PVT new tool | 1 | 1 | 1 | 1 | 1 | 1 | SGCC(T=1.0mm)/NA | Metal | 長江 | M13 |
|  | 4 |  |  |  |  |  | STD_COLUMN PARTITION-4 TRITON |  |  | 4 | 4 | 4 | 4 | 4 | 4 | Standoff | Purchase | 長江 |  |
|  | 3 | B34.0110D.0001 | B34.0110D.0001 | B34.0110D.0001 | B34.0110D.0001 | BRKT PARTITION SUPPORTER REAR BRCA | PARTITION SUPPORTER REAR TRITON |  | PVT new tool | 2 | 2 | 2 | 2 | 2 | 2 | SGCC(T=1.0mm)/NA | Metal | 信柏 | M14 |
|  | 3 | B34.0110B.0001 | B34.0110B.0001 | B34.0110B.0001 | B34.0110B.0001 | BRKT PARTITION SUPPORTER FRONT BRCA | PARTITION SUPPORTER FRONT TRITON |  | PVT new tool | 2 | 2 | 2 | 2 | 2 | 2 | SGCC(T=1.0mm)/NA | Metal | 長江 | M15 |
|  | 3 |  | B33.01117.0001 | B33.01117.0001 | B33.01117.0001 | HLDR HONEYCOMB BRCA | HONEYCOMB_HOLDER |  | PVT new tool | 4 | 4 | 4 | 4 | 4 | 4 | SGCC(T=0.8mm)/NA | Metal | 長江 | M29-1 |
|  | 3 | B33.01111.0001 | B33.01111.0001 | B33.01111.0001 | B33.01111.0001 | BRKT DUMMY FRONT PANEL SAS HD BRCA | DUMMY FRONT PANEL SAS HD BRACKET |  | PVT new tool | 0 | 0 | 1 | 1 | 1 | 1 | SGCC(T=1.0mm)/NA | Metal | 長江 | M29 |
|  | 3 | B33.0110G.0001 | B33.0110G.0001 | B33.0110G.0001 | B33.0110G.0001 | BRKT FAN TRAY BRCA | 02-FAN TRAY TRITON |  | PVT new tool | 2 | 2 | 2 | 2 | 2 | 2 | SGCC(T=1.0mm)/NA | Metal | 長江 | M20 |
|  | 3 |  | B33.01116.0001 | B33.01116.0001 | B33.01116.0001 | BRKT REMOVABLE CABLE TRACK BRCA | REMOVABLE BKT CABLE TRACK TRITON DVT |  |  | 1 | 1 | 1 | 1 | 1 | 1 | Assy | Assy | 長江 |  |
|  | 4 |  |  |  |  |  | REMOVABLE BKT CABLE TRACK TRITON DVT |  | PVT new tool | 1 | 1 | 1 | 1 | 1 | 1 | SGCC(T=1.0mm)/NA | Metal | 長江 | M28-1 |
|  | 4 |  |  |  |  |  | Thums screw(590B002) |  |  | 1 | 1 | 1 | 1 | 1 | 1 | Thumb screw | Purchase | Fivetech |  |
|  | 3 | B60.0110I.0001 | B60.0110I.0001 | B60.0110I.0001 | B60.0110I.0001 | ASSY 1ST F+R PARTITION BRCA | 1st F+R PARTITION ASSY |  |  | 2 | 2 | 2 | 2 | 2 | 2 |  |  | 宏塑 |  |
|  | 4 | B42.0110E.0001 | B42.0110E.0001 | B42.0110E.1001 | B42.0110E.1001 | HLDR PLASTIC PARTITION F 1ST ROW BRCA | 03-PLASTIC PARTITION FRONT 1ST ROW TRITON |  |  | 1 | 2 | 1 | 2 | 1 | 2 | Assy | Assy |  |  |
|  | 5 |  |  |  |  |  | 04-PLASTIC PARTITION FRONT 1ST ROW TRITON |  | DVT new tool | 1 | 2 | 1 | 2 | 1 | 2 | PC(Sabic Lexan 945A)/NA | Plastic | 宏塑 | P15 |
|  | 5 |  |  |  |  |  | INSERT_NUT M3X0.5_L4 |  |  | 5 | 10 | 5 | 10 | 5 | 10 | INSERT NUT | Purchase | 宏塑 |  |
|  | 5 |  |  |  |  |  | INSERT_NUT M2X0.4_L3 |  |  | 4 | 8 | 4 | 8 | 4 | 8 | INSERT NUT | Purchase | 宏塑 |  |
|  | 4 | B42.0110F.0001 | B42.0110F.0001 | B42.0110F.1001 | B42.0110F.1001 | HLDR PLASTIC PARTITION R DOUBLESHOT BRCA | 02-PLASTIC PARTITION REAR TRITON |  | DVT new tool | 1 | 2 | 1 | 2 | 1 | 2 | 雙料射出: 硬膠PC(Sabic Lexan 945A) 軟膠TPU(Elastollan 1175A10W) /NA | Plastic | 宏塑 | P16 |
|  | 4 | B33.0110Q.0001 | B33.0110Q.0001 | B33.0110Q.0001 | B33.0110Q.0001 | BRKT PARTITION SUPPORT BKT BRCA | 02-SUPPORT BKT PARTITION TRITON |  | PVT new tool | 1 | 2 | 1 | 2 | 1 | 2 | SUS301 1/2H (T=0.8mm)/NA | Metal | 宏塑 | M18 |
|  | 4 | B42.01113.0001 | B42.01113.0001 | B42.01113.0001 | B42.01113.0001 | LENS PARTITION SHORT LIGHT PIPE BRCA | Short light pipe |  | EVT opened tool | 6 | 12 | 6 | 12 | 6 | 12 | PC/NA Color:Transparent | Plastic | 宏塑 | P18 |
|  | 4 | 086.0007F.0845 | 086.0007F.0845 | 086.000KN.0945 | 086.000KN.0945 | SCRW TAP FLT M3*L5 NI | SCREW_086.000KN.0945 |  |  | 4 | 8 | 4 | 8 | 4 | 8 | Screw | Purchase | 文豪 | uses:  4  for inner partiton support BKT to partition |
|  | 4 | 86.00J00.645 | 86.00J00.645 | 86.00J00.645 | 86.00J00.645 | SCRW FLAT M3-P0.5 BLACK NYLOK | SCREW_86.00J00.645 |  |  | 1 | 2 | 1 | 2 | 1 | 2 | Screw | Purchase | 文豪 | uses:  1  for front partition to rear partition |
|  | 3 | B60.0110J.0001 | B60.0110J.0001 | B60.0110J.0001 | B60.0110J.0001 | ASSY MIDDLE F+R PARTITION BRCA | F+R PARTITION ASSY |  |  | 10 | 10 | 10 | 10 | 10 | 10 |  |  | 宏塑 |  |
|  | 4 | B42.0110G.0001 | B42.0110G.0001 | B42.0110G.1001 | B42.0110G.1001 | HLDR PLASTIC PARTITION F DOUBLESHOT BRCA | 02-PLASTIC PARTITION FRONT TRITON |  |  | 1 | 10 | 1 | 10 | 1 | 10 | Assy | Assy |  |  |
|  | 5 |  |  |  |  |  | 03-PLASTIC PARTITION FRONT TRITON |  | DVT new tool | 1 | 10 | 1 | 10 | 1 | 10 | 雙料射出: 硬膠PC(Sabic Lexan 945A) 軟膠TPU(Elastollan 1175A10W) /NA | Plastic | 宏塑 | P17 |
|  | 5 |  |  |  |  |  | INSERT_NUT M3X0.5_L4 |  |  | 6 | 60 | 6 | 60 | 6 | 60 | INSERT NUT | Purchase | 宏塑 |  |
|  | 4 | B42.0110F.0001 | B42.0110F.0001 | B42.0110F.1001 | B42.0110F.1001 | HLDR PLASTIC PARTITION R DOUBLESHOT BRCA | REAR PARTITION ASSY |  | DVT new tool | 1 | 10 | 1 | 10 | 1 | 10 | 雙料射出: 硬膠PC(Sabic Lexan 945A) 軟膠TPU(Elastollan 1175A10W) /NA |  | 宏塑 | P16 |
|  | 4 | B33.0110Q.0001 | B33.0110Q.0001 | B33.0110Q.0001 | B33.0110Q.0001 | BRKT PARTITION SUPPORT BKT BRCA | 02-SUPPORT BKT PARTITION TRITON |  | PVT new tool | 1 | 10 | 1 | 10 | 1 | 10 | SUS301 1/2H (T=0.8mm)/NA | Metal | 宏塑 | M18 |
|  | 4 | B42.01114.0001 | B42.01114.0001 | B42.01114.0001 | B42.01114.0001 | LENS PARTITION LIGHT PIPE BRCA | 02-LIGHT PIPE HDD TRITON |  | EVT opened tool | 6 | 60 | 6 | 60 | 6 | 60 | PC/NA Color:Transparent | Plastic | 宏塑 | P19 |
|  | 4 | 086.0007F.0845 | 086.0007F.0845 | 086.000KN.0945 | 086.000KN.0945 | SCRW TAP FLT M3*L5 NI | SCREW_086.000KN.0945 |  |  | 4 | 40 | 4 | 40 | 4 | 40 | Screw | Purchase | 文豪 | uses:  20  for inner partiton support BKT to partition |
|  | 4 | 86.00J00.645 | 86.00J00.645 | 86.00J00.645 | 86.00J00.645 | SCRW FLAT M3-P0.5 BLACK NYLOK | SCREW_86.00J00.645 |  |  | 1 | 10 | 1 | 10 | 1 | 10 | Screw | Purchase | 文豪 | uses:  5  for front partition to rear partition |
|  | 3 | B60.0110K.0001 | B60.0110K.0001 | B60.0110K.0001 | B60.0110K.0001 | ASSY 7TH F+R PARTITION BRCA | 7th F+R PARTITION ASSY |  |  | 2 | 2 | 2 | 2 | 2 | 2 |  |  | 宏塑 |  |
|  | 4 | B42.0110G.0001 | B42.0110G.0001 | B42.0110G.1001 | B42.0110G.1001 | HLDR PLASTIC PARTITION F DOUBLESHOT BRCA | 02-PLASTIC PARTITION FRONT TRITON |  |  | 1 | 2 | 1 | 2 | 1 | 2 | Assy | Assy |  |  |
|  | 5 |  |  |  |  |  | 03-PLASTIC PARTITION FRONT TRITON |  | DVT new tool | 1 | 2 | 1 | 2 | 1 | 2 | 雙料射出: 硬膠PC(Sabic Lexan 945A) 軟膠TPU(Elastollan 1175A10W) /NA | Plastic | 宏塑 | P17 |
|  | 5 |  |  |  |  |  | INSERT_NUT M3X0.5_L4 |  |  | 6 | 12 | 6 | 12 | 6 | 12 | INSERT NUT | Purchase | 宏塑 |  |
|  | 4 | B42.0110F.0001 | B42.0110F.0001 | B42.0110F.1001 | B42.0110F.1001 | HLDR PLASTIC PARTITION R DOUBLESHOT BC | 02-PLASTIC PARTITION REAR TRITON |  | DVT new tool | 1 | 2 | 1 | 2 | 1 | 2 | 雙料射出: 硬膠PC(Sabic Lexan 945A) 軟膠TPU(Elastollan 1175A10W) /NA | Plastic | 宏塑 | P16 |
|  | 4 | B33.0110Q.0001 | B33.0110Q.0001 | B33.0110Q.0001 | B33.0110Q.0001 | BRKT PARTITION SUPPORT BKT BRCA | 02-SUPPORT BKT PARTITION TRITON |  | PVT new tool | 1 | 2 | 1 | 2 | 1 | 2 | SUS301 1/2H (T=0.8mm)/NA | Metal | 宏塑 | M18 |
|  | 4 | 086.0007F.0845 | 086.0007F.0845 | 086.000KN.0945 | 086.000KN.0945 | SCRW TAP FLT M3*L5 NI | SCREW_086.000KN.0945 |  |  | 4 | 8 | 4 | 8 | 4 | 8 | Screw | Purchase | 文豪 | uses:  4  for inner partiton support BKT to partition |
|  | 4 | 86.00J00.645 | 86.00J00.645 | 86.00J00.645 | 86.00J00.645 | SCRW FLAT M3-P0.5 BLACK NYLOK | SCREW_86.00J00.645 |  |  | 1 | 2 | 1 | 2 | 1 | 2 | Screw | Purchase | 文豪 | uses:  1  for front partition to rear partition |
| 移至此階組裝 ,原舊料號B40.0110C.0001 | 4 |  |  |  | B40.0110C.0002 | LBL,HDD,BLUE,TRITON |  |  |  | 1 | 2 | 1 | 2 | 1 | 2 |  | Purchase | 正峰 |  |
|  | 3 |  |  | B60.0110Z.0001 | B60.0110Z.0001 | ASSY HDD LATCH BC | ASSY HDD LATCH |  |  | 72 | 72 | 72 | 72 | 72 | 72 |  |  |  |  |
|  | 4 | B34.01106.0001 | B34.01106.0001 | B34.01106.0001 | B34.01106.0001 | HDD LATCH 5TEK BRCA | HDD_LATCH |  | EVT opened tool | 1 | 72 | 1 | 72 | 1 | 72 |  | Purchase | Fivetech |  |
|  | 4 | B47.01115.0001 | B47.01115.0001 | B47.01115.0001 | B47.01115.0001 | HDD LATCH RUBBER | LATCH RUBBER 0.5MM |  |  | 1 | 72 | 1 | 72 | 1 | 72 | TPE 硬度65度(145*15*0.5T) | Purchase | 普詮 |  |
|  | 4 | B47.01116.0001 | B47.01116.0001 | B47.01116.0001 | B47.01116.0001 | HDD LATCH BOTTOM MYLAR | HDD Latch bottom mylar |  |  | 1 | 72 | 1 | 72 | 1 | 72 | Mylar | Purchase | 德竹 |  |
|  | 4 | B47.01117.0001 | B47.01117.0001 | B47.01117.0001 | B47.01117.0001 | HDD LATCH SPONGE | HDD Latch sponge |  |  | 1 | 72 | 1 | 72 | 1 | 72 | Sponge(E4382) | Purchase | 德竹 |  |
|  | 3 | B34.0110H.0001 | B42.0111P.0001 | B42.0111P.0001 | B42.0111P.0001 | CVR DRAWER REAR TOP COVER BRCA | 03-DRAWER REAR TOP COVER  TRITON DVT |  | PVT new tool | 1 | 1 | 1 | 1 | 1 | 1 | PC+ABS/NA  Color:Pantone 375C 局部鍍導電漆 | Plastic | 信柏 | P11 |
|  | 3 | B60.0110M.0001 | B60.0110M.0001 | B60.0110M.0001 | B60.0110M.0001 | 02-AIR-DUCT MONOLAKE TRITON | 02-AIR-DUCT MONOLAKE TRITON |  |  | 1 | 1 | 1 | 1 | 1 | 1 | Assy | Assy | 信柏 |  |
|  | 4 | B42.0110N.0001 | B42.0110N.0001 | B42.0110N.0001 | B42.0110N.0001 | CVR MONOLAKE AIR BAFFLE BRCA | 02-AIR-DUCT MONOLAKE TRITON |  | PVT new tool | 1 | 1 | 1 | 1 | 1 | 1 | PC+ABS/NA Color:Pantone 375C | Plastic | 信柏 | P1 |
|  | 4 | B42.01119.0001 | B42.01119.0001 | B42.01119.0001 | B42.01119.0001 | CABLE CLIP | Cable Clip(WTC-6) |  |  | 4 | 4 | 4 | 4 | 4 | 4 | Verdor PN: WCT-6 | Purchase | Kangyang |  |
|  | 3 | B42.0110U.0001 | B42.0110U.0001 | B42.0110U.0001 | B42.0110U.0001 | CVR REAR PARTITION AIR BAFFLE BRCA | REAR PARTITION AIR BAFFLE |  | PVT new tool | 2 | 2 | 2 | 2 | 2 | 2 | PC+ABS/NA Color:Pantone 375C | Plastic | 信柏 | P9 |
|  | 3 | B42.0110H.0001 | B42.0110H.0001 | B42.0110H.0001 | B42.0110H.0001 | HLDR SCC CARD GUIDE BRCA | 02-CARD GUIDE SCC  TRITON |  |  | 4 | 4 | 4 | 4 | 4 | 4 | Assy | Assy | 信柏 |  |
|  | 4 |  |  |  |  |  | 03-CARD GUIDE SCC  TRITON |  | PVT new tool | 1 | 4 | 1 | 4 | 1 | 4 | PC+ABS/NA | Plastic | 信柏 | P4 |
|  | 4 |  |  |  |  |  | INSERT_NUT M3X0.5_L4 |  |  | 1 | 4 | 1 | 4 | 1 | 4 | INSERT NUT | Purchase | 信柏 |  |
|  | 3 | B60.0110N.0001 | B60.0110N.0001 | B60.0110N.0001 | B60.0110N.0001 | ASSY MONOLAKE CARD GUIDE FRONT | ASSY MONOLAKE CARD GUIDE FRONT |  |  | 1 | 1 | 1 | 1 | 1 | 1 | Assy | Assy |  |  |
|  | 4 | B42.0110O.0001 | B42.0110O.0001 | B42.0110O.0001 | B42.0110O.0001 | HLDR MONOLAKE CARD GUIDE FRONT BRCA | MONO LAKE CARD GUIDE FRONT BRYCECANYON_DVT |  |  | 1 | 1 | 1 | 1 | 1 | 1 | Assy | Assy | 信柏 |  |
|  | 5 |  |  |  |  |  | CARD GUIDE MONOLAKE FRONT BRYCECANYON_DVT |  | PVT new tool | 1 | 1 | 1 | 1 | 1 | 1 | PC+ABS/NA | Plastic | 信柏 | P2 |
|  | 5 |  |  |  |  |  | INSERT_NUT M3X0.5_L4 |  |  | 1 | 1 | 1 | 1 | 1 | 1 | INSERT NUT | Purchase | 信柏 |  |
|  | 4 | B42.0110P.0001 | B42.0110P.0001 | B42.0110P.0001 | B42.0110P.0001 | MONO LAKE AIR DUCT BRCA | MONO LAKE AIR BAFFLE |  | PVT new tool | 2 | 2 | 2 | 2 | 2 | 2 | PC+ABS/NA | Plastic | 信柏 | P8 |
| 取消 | 4 | B42.01118.0001 | B42.01118.0001 | B42.01118.0001 | B42.01118.0001 | CHASSIS LED CABLE CLIP | LED cable clip |  |  | 2 | 2 | 2 | 2 | 2 | 2 | Verdor PN: WLL-16 | Purchase | Kangyang |  |
|  | 4 | 86.PA334.8R0 | 86.PA334.8R0 | 86.PA334.8R0 | 86.PA334.8R0 | SCRW M3 L8 PAN B TAP BZN | SCREW_86.PA334.8R0 |  |  | 2 | 2 | 2 | 2 | 2 | 2 | Screw | Purchase | 文豪 | uses:  2pcs for MONO LAKE AIR BAFFLE |
|  | 4 | B47.01119.0001 | B47.01119.0001 | B47.01119.0001 | B47.01119.0001 | MONOLAKE AIR BUFFLE SPONGE | Monolake air buffle sponge |  |  | 1 | 1 | 1 | 1 | 1 | 1 | Sponge(E4382) | Purchase | 德竹 |  |
|  | 3 | B42.0110Q.0001 | B42.0110Q.0001 | B42.0110Q.0001 | B42.0110Q.0001 | 02-CARD GUIDE MONOLAKE-REAR  TRITON | 02-CARD GUIDE MONOLAKE-REAR  TRITON |  | PVT new tool | 1 | 1 | 1 | 1 | 1 | 1 | PC+ABS/NA | Plastic | 信柏 | P3 |
|  | 3 | B47.01111.0001 | B47.01111.0001 | B47.01111.0001 | B47.01111.0001 | PLASTIC PLUG RIGHT | 03-PLASTIC SPOOL PART TRITON-R |  | PVT new tool | 7 | 7 | 7 | 7 | 7 | 7 | PC+ABS/NA | Plastic | 信柏 | P7 |
|  | 3 | B47.01112.0001 | B47.01112.0001 | B47.01112.0001 | B47.01112.0001 | PLASTIC PLUG LEFT | 03-PLASTIC SPOOL PART TRITON-L |  | PVT new tool | 6 | 6 | 6 | 6 | 6 | 6 | PC+ABS/NA | Plastic | 信柏 | P6 |
|  | 3 |  | B42.0111Q.0001 | B42.0111Q.0001 | B42.0111Q.0001 | HLDR POWAR CABLE GUILDING DVT BC | Assy power connector guiding |  |  | 1 | 1 | 1 | 1 | 1 | 1 | Assy | Assy | 信柏 |  |
|  | 4 |  |  |  |  |  | power connector guiding |  | PVT new tool | 1 | 1 | 1 | 1 | 1 | 1 | PC+ABS/NA | Plastic | 信柏 | P14 |
|  | 4 |  |  |  |  |  | INSERT_NUT M3X0.5_L3 |  |  | 1 | 1 | 1 | 1 | 1 | 1 | INSERT NUT | Purchase | 信柏 |  |
|  | 3 | B60.0110D.0001 | B60.0110D.0001 | B60.0110D.0001 | B60.0110D.0001 | LEFT PULL HANDLE DRAWER BRCA 5TECH | LEFT PULL_HANDLE_DRAWER |  | EVT opened tool | 1 | 1 | 1 | 1 | 1 | 1 |  | Purchase | Fivetech |  |
|  | 3 | B60.0110E.0001 | B60.0110E.0001 | B60.0110E.0001 | B60.0110E.0001 | RIGH PULL HANDLE DRAWER BRCA 5TECH | RIGHT PULL_HANDLE_DRAWER |  | EVT opened tool | 1 | 1 | 1 | 1 | 1 | 1 |  | Purchase | Fivetech |  |
|  | 3 |  |  |  | B34.01116.0001 | EMI HONEYCOMB BC | HONEYCOMB ASSY |  |  | 2 | 2 | 2 | 2 | 2 | 2 | HONEYCOMB | Purchase | FRD |  |
|  | 3 |  |  | B34.01118.0001 | B34.01118.0001 | EMI GASKET FRONT PANEL-1 BC | FRONT PANEL GASKET1 |  |  | 1 | 1 | 1 | 1 | 1 | 1 | Gasket | Purchase | 德竹 |  |
|  | 3 |  |  | B34.01119.0001 | B34.01119.0001 | EMI GASKET FRONT PANEL-2 BC | FRONT PANEL GASKET2 |  |  | 4 | 4 | 4 | 4 | 4 | 4 | Gasket | Purchase | 德竹 |  |
|  | 3 |  |  | B34.0111A.0001 | B34.0111A.0001 | MI GASKET FRONT PANEL-3 BC | FRONT PANEL GASKET3 |  |  | 2 | 2 | 2 | 2 | 2 | 2 | Gasket | Purchase | 德竹 |  |
|  | 3 |  |  | B34.0111I.0001 | B34.0111I.0001 | EMI GASKET FRONT DOOR SIDE BC | FRONT DOOR SIDE GASKET |  |  | 1 | 1 | 1 | 1 | 1 | 1 | Gasket | Purchase | 德竹 |  |
|  | 3 |  |  | B34.0111J.0001 | B34.0111J.0001 | EMI GASKET FRONT DOOR TOP-BOT BC | FRONT DOOR TOP BOTTOM GASKET |  |  | 2 | 2 | 2 | 2 | 2 | 2 | Gasket | Purchase | 德竹 |  |
|  | 3 |  |  | B34.0111K.0001 | B34.0111K.0001 | EMI GASKET FRONT DOOR LOCK SIDE BC | FRONT DOOR LOCK SIDE GASKET |  |  | 2 | 2 | 2 | 2 | 2 | 2 | Gasket | Purchase | 德竹 |  |
|  | 3 |  |  | B34.0111E.0001 | B34.0111E.0001 | EMI GASKET SUPPORTER REAR BC | SUPPORTER REAR GASKET |  |  | 4 | 4 | 4 | 4 | 4 | 4 | GASKET | Purchase | 信柏 |  |
|  | 3 |  | B34.01110.0001 | B34.01110.0001 | B34.01110.0001 | EMI GASKET DRAWER REAR MID-TOP BC DVT | DRAWER REAR BUS BAR TOP GASKET |  |  | 1 | 1 | 1 | 1 | 1 | 1 | Gasket | Purchase | 德竹 |  |
|  | 3 |  | B34.01111.0001 | B34.01111.0001 | B34.01111.0001 | EMI GASKET DRAWER REAR MID-BOT BC DVT | DRAWER REAR BUS BAR BOTTOM GASKET |  |  | 1 | 1 | 1 | 1 | 1 | 1 | Gasket | Purchase | 德竹 |  |
|  | 3 |  | B34.01112.0001 | B34.01112.0001 | B34.01112.0001 | EMI GASKET DRAWER REAR L BC DVT | DRAWER REAR FAN TRAY TOP LEFT GASKET |  |  | 1 | 1 | 1 | 1 | 1 | 1 | Gasket | Purchase | 德竹 |  |
|  | 3 |  | B34.01113.0001 | B34.01113.0001 | B34.01113.0001 | EMI GASKET DRAWER REAR R BC DVT | DRAWER REAR FAN TRAY TOP RIGHT GASKET |  |  | 1 | 1 | 1 | 1 | 1 | 1 | Gasket | Purchase | 德竹 |  |
|  | 3 | B47.0110Z.0001 | B47.0110Z.0001 | B47.0110Z.0001 | B47.0110Z.0001 | SPONGE ON TRAPEZIUM STANDOFF (FRONT) | Front support bracket sponge |  |  | 2 | 2 | 2 | 2 | 2 | 2 | Sponge(E4382) | Purchase | 德竹 |  |
|  | 3 | B47.01113.0001 | B47.01113.0001 | B47.01113.0001 | B47.01113.0001 | SPONGE ON TRAPEZIUM STANDOFF (REAR) | Rear support sponge |  |  | 2 | 2 | 2 | 2 | 2 | 2 | Sponge(E4382) | Purchase | 德竹 |  |
|  | 3 | B40.0110F.0001 | B40.0110F.0001 | B40.0110F.0001 | B40.0110F.0001 | MYLAR WALL REAR | mylar_wall_rear |  |  | 1 | 1 | 1 | 1 | 1 | 1 | Mylar | Purchase | 德竹 |  |
|  | 3 | B40.0110E.0001 | B40.0110E.0001 | B40.0110E.0001 | B40.0110E.0001 | DRAWER REAR WALL MYLAR | DRAWER REAR WALL MYLAR |  |  | 2 | 2 | 2 | 2 | 2 | 2 | Mylar | Purchase | 德竹 |  |
|  | 3 |  | B47.0112Q.0001 | B47.0112Q.0001 | B47.0112Q.0001 | DRAWER REAR WALL MYLAR-2 | DRAWER REAR WALL MYLAR-2 |  |  | 1 | 1 | 1 | 1 | 1 | 1 | Mylar | Purchase | 德竹 |  |
|  | 3 | B47.0111M.0001 | B47.0111M.0001 | B47.0111M.0001 | B47.0111M.0001 | SPONGE DRAWER REAR WALL TO FAN TRAY | SPONGE DRAWER REAR WALL TO FAN TRAY |  |  | 2 | 2 | 2 | 2 | 2 | 2 | Sponge(E4382) | Purchase | 德竹 |  |
| 修改數量:6=>3 | 3 | B42.01118.0001 | B42.01118.0001 | B42.01118.0001 | B42.01118.0001 | CHASSIS LED CABLE CLIP | LED cable clip |  |  | 3 | 3 | 3 | 3 | 3 | 3 | Verdor PN: WLL-16 | Purchase | Kangyang | uses: 3 for 1st row partition |
|  | 3 | 38.21010.001 | 38.21010.001 | 38.21010.001 | 38.21010.001 | VELCRO TIE 12MM X 200MM | VCO19812-A |  |  | 2 | 2 | 2 | 2 | 2 | 2 | Verdor PN: VCO19812 | Purchase | Kangyang |  |
|  | 3 | 086.1A524.04R5 | 086.1A524.04R5 | 086.1A524.04R5 | 086.1A524.04R5 | SCRW PH M3*0.5 L4.5 SPECIAL | SCREW_086.1A524.04R5 |  |  | 2 | 2 | 2 | 2 | 2 | 2 | Screw | Purchase | 文豪 | uses: 2 for rotate door to front panel |
|  | 3 | 86.00T32.544 | 86.00T32.544 | 86.00T32.544 | 86.00T32.544 | SCRW WAFRE M3.0 L4 NYLOK | SCREW_86.00T32.544 |  |  | 13 | 13 | 13 | 13 | 13 | 13 | Screw | Purchase | 文豪 | uses:  4 for plastic spool to column partition-2 5 for plastic spool to column partition-3 4 for plastic spool to column partition-4 |
|  | 3 | 086.5AS24.0100 | 086.5AS24.0100 | 086.5AS24.0100 | 086.5AS24.0100 | SCRW MAC FLT M3-L10.5 NI SAE1018 | SCREW_086.5AS24.0100 |  |  | 56 | 56 | 56 | 56 | 56 | 56 | Screw | Purchase | 文豪 | uses:  56  for partition to side-wall |
|  | 3 | 086.8RS26.08R0 | 086.8RS26.08R0 | 086.8RS26.08R0 | 086.8RS26.08R0 | SCRW MAC SOCKET M4 L8 NI | SCREW_086.8RS26.08R0 |  |  | 6 | 6 | 6 | 6 | 6 | 6 | Screw | Purchase | 文豪 | uses:  6  for front handle |
|  | 3 | 86.5A534.4R0 | 86.00R06.644 | 86.00R06.644 | 86.00R06.644 | SCRW FLAT M3*L4 NYLOK | SCREW_86.00R06.644 |  |  | 21 | 21 | 21 | 21 | 21 | 21 | Screw | Purchase | 文豪 | uses: 2 for column partition-2 to column partition-4 4 for column partition-4 to SCC card guide 1 for power conn guiding to rear supporter 14 for Fan tray to rear wall |
|  | 3 |  |  |  | 086.1A324.06R0 | STEEL SCREW L800-SCRW_M3_L6_PAN_NYLOK | SCREW_086.1A324.06R0 |  |  | 8 | 8 | 8 | 8 | 8 | 8 | Screw | Purchase | 文豪 | uses:  4 for SCC card guide to column partiton-3 4 for Mono card guide to column partiton-2/3 |
|  | 3 | TBD | TBD | TBD | B34.0111L.0001 | SPG DRAWER FRONT WINDOW-TOP BC | SPRING |  |  | 1 | 1 | 1 | 1 | 1 | 1 | Spring | Purchase | 長江 | 長江幫忙找Source,WW提供規格 |
|  | 3 | TBD | TBD | TBD | B34.0111M.0001 | SPG DRAWER FRONT WINDOW-BOT BC | SPRING |  |  | 1 | 1 | 1 | 1 | 1 | 1 | Spring | Purchase | 長江 | 長江幫忙找Source,WW提供規格 |
|  | 3 |  | B40.0110L.0001 | B40.0110L.1001 | B40.0110L.1001 | LBL 678*100*0.5MM DRWAER WARNING-L BC |  |  |  | 1 | 1 | 1 | 1 | 1 | 1 |  | Purchase | 正峰 |  |
|  | 3 |  | B40.0110L.0011 | B40.0110L.2001 | B40.0110L.2001 | LBL 678*100*0.5MM DRWAER WARNING-R BC |  |  |  | 1 | 1 | 1 | 1 | 1 | 1 |  | Purchase | 正峰 |  |
|  | 3 | B40.0110J.0001 | B40.0110J.1001 | B40.0110J.1001 | B40.0110J.1001 | LBL,WHITE,HDD,NO.0~5,SCREW ICON,BC |  |  |  | 1 | 1 | 1 | 1 | 1 | 1 |  | Purchase | 正峰 |  |
|  | 3 | B40.0110J.0011 | B40.0110J.2001 | B40.0110J.2001 | B40.0110J.2001 | LBL,WHITE,HDD,NO.6~11,SCREW ICON,BC |  |  |  | 1 | 1 | 1 | 1 | 1 | 1 |  | Purchase | 正峰 |  |
|  | 3 | B40.0110J.0021 | B40.0110J.0021 | B40.0110J.0021 | B40.0110J.0021 | LBL,White,HDD,NO.12~17,Triton |  |  |  | 1 | 1 | 1 | 1 | 1 | 1 |  | Purchase | 正峰 |  |
|  | 3 | B40.0110J.0031 | B40.0110J.0031 | B40.0110J.0031 | B40.0110J.0031 | LBL,White,HDD,NO.18~23,Triton |  |  |  | 1 | 1 | 1 | 1 | 1 | 1 |  | Purchase | 正峰 |  |
|  | 3 | B40.0110J.0041 | B40.0110J.0041 | B40.0110J.0041 | B40.0110J.0041 | LBL,White,HDD,NO.24~29,Triton |  |  |  | 1 | 1 | 1 | 1 | 1 | 1 |  | Purchase | 正峰 |  |
|  | 3 | B40.0110J.0051 | B40.0110J.0051 | B40.0110J.0051 | B40.0110J.0051 | LBL,White,HDD,NO.30~35,Triton |  |  |  | 1 | 1 | 1 | 1 | 1 | 1 |  | Purchase | 正峰 |  |
|  | 3 | B40.0110K.0001 | B40.0110K.1001 | B40.0110K.1001 | B40.0110K.1001 | LBL,BLACK,HDD,NO.0~5,SCREW ICON,BC |  |  |  | 1 | 1 | 1 | 1 | 1 | 1 |  | Purchase | 正峰 |  |
|  | 3 | B40.0110K.0011 | B40.0110K.0011 | B40.0110K.0011 | B40.0110K.0011 | LBL,Black,HDD,NO.6~11,Triton |  |  |  | 1 | 1 | 1 | 1 | 1 | 1 |  | Purchase | 正峰 |  |
|  | 3 | B40.0110K.0021 | B40.0110K.0021 | B40.0110K.0021 | B40.0110K.0021 | LBL,Black,HDD,NO.12~17,Triton |  |  |  | 1 | 1 | 1 | 1 | 1 | 1 |  | Purchase | 正峰 |  |
|  | 3 | B40.0110K.0031 | B40.0110K.2001 | B40.0110K.2001 | B40.0110K.2001 | LBL,BLACK,HDD,NO.18~23,SCREW ICON,BC |  |  |  | 1 | 1 | 1 | 1 | 1 | 1 |  | Purchase | 正峰 |  |
|  | 3 | B40.0110K.0041 | B40.0110K.0041 | B40.0110K.0041 | B40.0110K.0041 | LBL,Black,HDD,NO.24~29,Triton |  |  |  | 1 | 1 | 1 | 1 | 1 | 1 |  | Purchase | 正峰 |  |
|  | 3 | B40.0110K.0051 | B40.0110K.0051 | B40.0110K.0051 | B40.0110K.0051 | LBL,Black,HDD,NO.30~35,Triton |  |  |  | 1 | 1 | 1 | 1 | 1 | 1 |  | Purchase | 正峰 |  |
| 取消,移至ASSY 7TH F+R PARTITION BRCA 子階 | 3 | B40.0110C.0001 | B40.0110C.0001 | B40.0110C.0001 | B40.0110C.0001 | LBL,HDD,Black,Triton |  |  |  | 2 | 2 | 2 | 2 | 2 | 2 |  | Purchase | 正峰 |  |
|  | 3 | B40.01108.0001 | B40.01108.0001 | B40.01108.0001 | B40.01108.0001 | LBL,White,14.5*6.5*0.125mm,Mono Lake,Triton |  |  |  | 4 | 4 | 4 | 4 | 4 | 4 |  | Purchase | 正峰 | SCC X 2; Monolake X 2 |
|  | 3 | B40.01109.0011 | B40.01109.0011 | B40.01109.0011 | B40.01109.0011 | LBL,BLACK,14.5*6.5*0.125MM,MONO LAKE |  |  |  | 4 | 4 | 4 | 4 | 4 | 4 |  | Purchase | 正峰 | SCC X 2; Monolake X 2 |
|  | 3 |  |  |  | B40.0110N.0001 | LBL ARTPAPER 24*12*0.08MM FAN-L,BC |  |  |  | 2 | 2 | 0 | 0 | 2 | 2 |  | Purchase | 正峰 |  |
|  | 3 |  |  |  | B40.0110O.0001 | LBL ARTPAPER 24*12*0.08MM FAN-R,BC |  |  |  | 2 | 2 | 0 | 0 | 2 | 2 |  | Purchase | 正峰 |  |
|  | 2 | B60.0110O.0001 | B60.0110O.0001 | B60.0110O.0001 | B60.0110O.0011 | ASSY IO MODULE BKT M.2 BRCA | 02-IO MODULE BRACKET TRITON M.2 |  |  | 0 | 0 | 2 | 2 | 0 | 0 |  |  |  |  |
|  | 3 | B33.0110Z.0001 | B33.0110Z.0001 | B33.0110Z.0001 | B33.0110Z.0001 | BRKT IOM BKT M.2 BRCA | 03-IO MODULE BRACKET TRITON M.2 |  |  | 0 | 0 | 1 | 2 | 0 | 0 | Assy | Assy | 長江 |  |
|  | 4 |  |  |  |  |  | 04-IO MODULE BRACKET TRITON M.2 |  | PVT new tool | 0 | 0 | 1 | 2 | 0 | 0 | SGCC(T=0.8mm)/NA | Metal | 長江 | M17 |
|  | 4 |  |  |  |  |  | STD_PERSONALITY_BKT-1 ACKBAR |  |  | 0 | 0 | 11 | 22 | 0 | 0 | Standoff | Purchase | 長江 |  |
|  | 4 |  |  |  |  |  | STD_PERSONALITY_BKT-2 ACKBAR |  |  | 0 | 0 | 2 | 4 | 0 | 0 | Standoff | Purchase | 長江 |  |
|  | 4 |  |  |  |  |  | STD_PERSONALITY_BKT-2 TRITON |  |  | 0 | 0 | 1 | 2 | 0 | 0 | Standoff | Purchase | 長江 |  |
|  | 3 | B60.0110C.0001 | B60.0110C.0001 | B60.0110C.0001 | B60.0110C.0001 | IOM LATCH BRCA 5TECH | IOM_LATCH_TRITON |  | EVT opened tool | 0 | 0 | 1 | 2 | 0 | 0 | Latch | Purchase | Fivetech |  |
|  | 3 | B34.0110R.0001 | B34.0110R.0001 | B34.0110R.0001 | B34.0110R.0001 | SPG IOM LATCH BRCA 5TECH | SP-511B042-X01 |  |  | 0 | 0 | 1 | 2 | 0 | 0 | Stainless steel | Purchase | Fivetech |  |
|  | 3 | B33.01110.0001 | B33.01110.0001 | B33.01110.0001 | B33.01110.0001 | IOM LATCH HINGE | latch_hinge_stdf_hb-168 |  |  | 0 | 0 | 1 | 2 | 0 | 0 | Hinge | Purchase | 文豪 |  |
|  | 3 |  | B47.0112J.0001 | B47.0112J.0001 | B47.0112J.0001 | MYLAR IOM BKT M.2 DVT BC | MYLAR IO MODULE BRACKET TRITON IOC |  |  | 0 | 0 | 1 | 2 | 0 | 0 | Mylar | Purchase | 德竹 |  |
|  | 3 |  | B47.0112U.0001 | B47.0112U.0001 | B47.0112U.0001 | SPONGE IOM BKT BOT LEFT BC | IOM BRACKET SPONGE BOT LEFT |  |  | 0 | 0 | 1 | 2 | 0 | 0 | Sponge(YU356) | Purchase | 德竹 |  |
|  | 3 |  | B47.0112V.0001 | B47.0112V.0001 | B47.0112V.0001 | SPONGE IOM BKT BOT RIGHT BC | IOM BRACKET SPONGE BOT RIGHT |  |  | 0 | 0 | 1 | 2 | 0 | 0 | Sponge(YU356) | Purchase | 德竹 |  |
|  | 3 |  |  | B34.0111B.0001 | B34.0111B.0001 | EMI GASKET IOM TOP LEFT BC | IOM LEFT GASKET |  |  | 0 | 0 | 1 | 2 | 0 | 0 | Gasket | Purchase | 德竹 |  |
|  | 3 |  |  | B34.0111C.0001 | B34.0111C.0001 | EMI GASKET IOM TOP MID BC | IOM MIDDLE GASKET |  |  | 0 | 0 | 1 | 2 | 0 | 0 | Gasket | Purchase | 德竹 |  |
|  | 3 |  |  | B34.0111D.0001 | B34.0111D.0001 | EMI GASKET IOM TOP RIGHT BC | IOM RIGHT GASKET |  |  | 0 | 0 | 1 | 2 | 0 | 0 | Gasket | Purchase | 德竹 |  |
|  | 3 |  |  | B34.0111F.0001 | B34.0111F.0001 | EMI GASKET IOM MINI SAS TOP BC | IOM MINI SAS TOP GASKET |  |  | 0 | 0 | 1 | 2 | 0 | 0 | Gasket | Purchase | 德竹 |  |
|  | 3 |  |  | B34.0111G.0001 | B34.0111G.0001 | EMI GASKET IOM MINI SAS BOT BC | IOM MINI SAS BOTTOM GASKET |  |  | 0 | 0 | 1 | 2 | 0 | 0 | Gasket | Purchase | 德竹 |  |
|  | 3 |  |  | B34.0111H.0001 | B34.0111H.0001 | EMI GASKET IOM USB BC | IOM USB GASKET |  |  | 0 | 0 | 1 | 2 | 0 | 0 | Gasket | Purchase | 德竹 |  |
|  | 3 |  |  |  | B47.0112Z.0001 | PORON SUPERCAP BOT BC | PORON SUPERCAP |  |  | 0 | 0 | 1 | 2 | 0 | 0 |  | Purchase | 德竹 |  |
|  | 3 |  |  |  | 038.21001.0001 | VELCRO TIE SUPERCAP BC | 魔鬼氈 |  |  | 0 | 0 | 2 | 4 | 0 | 0 |  | Purchase | Kangyang |  |
|  | 2 |  |  | B60.01110.0001 | B60.01110.0001 | ASSY IO MODULE BRACKET DUMMY BRCA | 03-IO MODULE BRACKET TRITON DUMMY |  |  | 2 | 2 | 0 | 0 | 1 | 1 |  |  |  |  |
|  | 3 | B34.0110J.0001 | B34.0110J.0001 | B34.0110J.0001 | B34.0110J.0001 | BRKT IOM BKT DUMMY BRCA | 04-IO MODULE BRACKET TRITON DUMMY |  |  | 1 | 2 | 0 | 0 | 1 | 1 | Assy | Assy | 長江 |  |
|  | 4 |  |  |  |  |  | 04-IO MODULE BRACKET TRITON DUMMY |  | PVT new tool | 1 | 2 | 0 | 0 | 1 | 1 | SGCC(T=0.8mm)/NA | Metal | 長江 | M16-1 |
|  | 4 |  |  |  |  |  | STD_PERSONALITY_BKT-2 TRITON |  |  | 1 | 2 | 0 | 0 | 1 | 1 | Standoff | Purchase | 長江 |  |
|  | 3 | B60.0110C.0001 | B60.0110C.0001 | B60.0110C.0001 | B60.0110C.0001 | IOM LATCH BRCA 5TECH | IOM_LATCH_TRITON |  | EVT opened tool | 1 | 2 | 0 | 0 | 1 | 1 | Latch | Purchase | Fivetech |  |
|  | 3 | B34.0110R.0001 | B34.0110R.0001 | B34.0110R.0001 | B34.0110R.0001 | SPG IOM LATCH BRCA 5TECH | SP-511B042-X01 |  |  | 1 | 2 | 0 | 0 | 1 | 1 | Stainless steel | Purchase | Fivetech |  |
|  | 3 | B33.01110.0001 | B33.01110.0001 | B33.01110.0001 | B33.01110.0001 | IOM LATCH HINGE | latch_hinge_stdf_hb-168 |  |  | 1 | 2 | 0 | 0 | 1 | 1 | Hinge | Purchase | 文豪 |  |
|  | 3 |  | B47.0112U.0001 | B47.0112U.0001 | B47.0112U.0001 | SPONGE IOM BKT BOT LEFT BC | IOM BRACKET SPONGE BOT LEFT |  |  | 1 | 2 | 0 | 0 | 1 | 1 | Sponge(YU356) | Purchase | 德竹 |  |
|  | 3 |  | B47.0112V.0001 | B47.0112V.0001 | B47.0112V.0001 | SPONGE IOM BKT BOT RIGHT BC | IOM BRACKET SPONGE BOT RIGHT |  |  | 1 | 2 | 0 | 0 | 1 | 1 | Sponge(YU356) | Purchase | 德竹 |  |
|  | 3 |  |  | B34.0111B.0001 | B34.0111B.0001 | EMI GASKET IOM TOP LEFT BC | IOM LEFT GASKET |  |  | 1 | 2 | 0 | 0 | 1 | 1 | Gasket | Purchase | 德竹 |  |
|  | 3 |  |  | B34.0111C.0001 | B34.0111C.0001 | EMI GASKET IOM TOP MID BC | IOM MIDDLE GASKET |  |  | 1 | 2 | 0 | 0 | 1 | 1 | Gasket | Purchase | 德竹 |  |
|  | 3 |  |  | B34.0111D.0001 | B34.0111D.0001 | EMI GASKET IOM TOP RIGHT BC | IOM RIGHT GASKET |  |  | 1 | 2 | 0 | 0 | 1 | 1 | Gasket | Purchase | 德竹 |  |
|  | 2 | B60.0110P.0001 | B60.0110P.0001 | B60.0110P.0001 | B60.0110P.0011 | ASSY IO MODULE BKT IOC BRCA | 02-IO MODULE BRACKET TRITON IOC |  |  | 0 | 0 | 0 | 0 | 1 | 1 |  |  |  |  |
|  | 3 | B34.0110I.0001 | B34.0110I.0001 | B34.0110I.0001 | B34.0110I.0001 | BRKT IOM BKT IOC BRCA | 03-IO MODULE BRACKET TRITON IOC |  |  | 0 | 0 | 0 | 0 | 1 | 1 | Assy | Assy | 長江 |  |
|  | 4 |  |  |  |  |  | 04-IO MODULE BRACKET TRITON IOC |  | PVT new tool | 0 | 0 | 0 | 0 | 1 | 1 | SGCC(T=0.8mm)/NA | Metal | 長江 | M16 |
|  | 4 |  |  |  |  |  | STD_PERSONALITY_BKT-1 ACKBAR |  |  | 0 | 0 | 0 | 0 | 9 | 9 | Standoff | Purchase | 長江 |  |
|  | 4 |  |  |  |  |  | STD_PERSONALITY_BKT-2 ACKBAR |  |  | 0 | 0 | 0 | 0 | 2 | 2 | Standoff | Purchase | 長江 |  |
|  | 4 |  |  |  |  |  | STD_PERSONALITY_BKT-2 TRITON |  |  | 0 | 0 | 0 | 0 | 1 | 1 | Standoff | Purchase | 長江 |  |
|  | 3 | B60.0110C.0001 | B60.0110C.0001 | B60.0110C.0001 | B60.0110C.0001 | IOM LATCH BRCA 5TECH | IOM_LATCH_TRITON |  | EVT opened tool | 0 | 0 | 0 | 0 | 1 | 1 | Latch | Purchase | Fivetech |  |
|  | 3 | B34.0110R.0001 | B34.0110R.0001 | B34.0110R.0001 | B34.0110R.0001 | SPG IOM LATCH BRCA 5TECH | SP-511B042-X01 |  |  | 0 | 0 | 0 | 0 | 1 | 1 | Stainless steel | Purchase | Fivetech |  |
|  | 3 | B33.01110.0001 | B33.01110.0001 | B33.01110.0001 | B33.01110.0001 | IOM LATCH HINGE | latch_hinge_stdf_hb-168 |  |  | 0 | 0 | 0 | 0 | 1 | 1 | Hinge | Purchase | 文豪 |  |
|  | 3 |  |  |  | B47.01130.0001 | MYLAR IOM BKT IOC BC | MYLAR IOM IOC |  |  | 0 | 0 | 0 | 0 | 1 | 1 | Mylar | Purchase | 德竹 |  |
|  | 3 |  | B47.0112U.0001 | B47.0112U.0001 | B47.0112U.0001 | SPONGE IOM BKT BOT LEFT BC | IOM BRACKET SPONGE BOT LEFT |  |  | 0 | 0 | 0 | 0 | 1 | 1 | Sponge(YU356) | Purchase | 德竹 |  |
|  | 3 |  | B47.0112V.0001 | B47.0112V.0001 | B47.0112V.0001 | SPONGE IOM BKT BOT RIGHT BC | IOM BRACKET SPONGE BOT RIGHT |  |  | 0 | 0 | 0 | 0 | 1 | 1 | Sponge(YU356) | Purchase | 德竹 |  |
|  | 3 |  |  | B34.0111B.0001 | B34.0111B.0001 | EMI GASKET IOM TOP LEFT BC | IOM LEFT GASKET |  |  | 0 | 0 | 0 | 0 | 1 | 1 | Gasket | Purchase | 德竹 |  |
|  | 3 |  |  | B34.0111C.0001 | B34.0111C.0001 | EMI GASKET IOM TOP MID BC | IOM MIDDLE GASKET |  |  | 0 | 0 | 0 | 0 | 1 | 1 | Gasket | Purchase | 德竹 |  |
|  | 3 |  |  | B34.0111D.0001 | B34.0111D.0001 | EMI GASKET IOM TOP RIGHT BC | IOM RIGHT GASKET |  |  | 0 | 0 | 0 | 0 | 1 | 1 | Gasket | Purchase | 德竹 |  |
|  | 3 |  |  | B34.0111F.0001 | B34.0111F.0001 | EMI GASKET IOM MINI SAS TOP BC | IOM MINI SAS TOP GASKET |  |  | 0 | 0 | 0 | 0 | 1 | 1 | Gasket | Purchase | 德竹 |  |
|  | 3 |  |  | B34.0111G.0001 | B34.0111G.0001 | EMI GASKET IOM MINI SAS BOT BC | IOM MINI SAS BOTTOM GASKET |  |  | 0 | 0 | 0 | 0 | 1 | 1 | Gasket | Purchase | 德竹 |  |
|  | 3 |  |  | B34.0111H.0001 | B34.0111H.0001 | EMI GASKET IOM USB BC | IOM USB GASKET |  |  | 0 | 0 | 0 | 0 | 1 | 1 | Gasket | Purchase | 德竹 |  |
|  | 2 | B60.01107.0001 | B60.01107.0001 | B60.01107.0001 | B60.01107.0011 | ASSY FAN CAGE BRCA | ASST FAN CAGE TRITON |  |  | 1 | 2 | 1 | 2 | 1 | 2 | Assy | Assy |  |  |
|  | 3 | B33.0110I.0001 | B33.0110I.0001 | B33.0110I.0001 | B33.0110I.0001 | HLDR FAN CAGE BRCA | 03-ASSY FAN CAGE TRITON |  |  | 1 | 2 | 1 | 2 | 1 | 2 | Assy | Assy | 長江 |  |
|  | 4 |  |  |  |  |  | NEW_FAN_CAGE_PL |  | PVT new tool | 1 | 2 | 1 | 2 | 1 | 2 | SGCC(T=0.8mm)/NA | Metal | 長江 | M21 |
|  | 4 |  |  |  |  |  | TR_ST_FAN |  |  | 2 | 4 | 2 | 4 | 2 | 4 | Standoff | Purchase | 長江 |  |
|  | 3 | B33.0110S.0001 | B33.0110S.0001 | B33.0110S.0001 | B33.0110S.0001 | BRKT FAN CAGE HANDLE | NEW_FAN_HANDLE_ASSY |  |  | 1 | 2 | 1 | 2 | 1 | 2 | Assy | Assy | 長江 |  |
|  | 4 |  |  |  |  |  | NEW_TR_ARM_PL |  | PVT new tool | 1 | 2 | 1 | 2 | 1 | 2 | SGCC(T=0.8mm)/NA | Metal | 長江 | M22 |
|  | 4 |  |  |  |  |  | Plunger (57-122-153-01-5) |  |  | 1 | 2 | 1 | 2 | 1 | 2 | Standoff | Purchase | Fivetech |  |
|  | 3 | B42.01116.0001 | B42.01116.0001 | B42.01116.0001 | B42.01116.0001 | FAN HOLDER OF LIGHT PIPE | LED5-1S |  |  | 2 | 4 | 2 | 4 | 2 | 4 | Verdor PN: LED-1S | Purchase | Kangyang |  |
|  | 3 |  |  |  | B47.0112S.0001 | RUBBER ANTI-VIBRATE GROMMET TGM-145V01(B) | TGM-145V01(B) |  |  | 4 | 8 | 8 | 16 | 4 | 8 |  | Purchase | Kangyang |  |
| B60.0110T.0021/B60.0110U.0021修改數量:4=>2 | 3 | B42.0110X.0001 | B42.0110X.0001 | B42.0110X.0001 | B42.0110X.0002 | LIGHT PIPE FAN CAGE BRCA | NEW_LIGHT_PIPE_FAN_BRYCE_CANYON |  | PVT new tool | 1 | 2 | 2 | 4 | 1 | 2 | PC/NA Color:Transparent | Plastic | 信柏 | P5 |
|  | 3 |  | B47.0112M.0001 | B47.0112M.0001 | B47.0112M.0001 | SPONGE OUTER FONRT FAN CAGE DVT BC |  |  |  | 6 | 12 | 6 | 12 | 6 | 12 | Mylar+Sponge(HT800) | Purchase | 德竹 |  |
|  | 3 |  | B47.0112T.0001 | B47.0112T.0001 | B47.0112T.0001 | SPONGE OUTER FONRT MID FAN CAGE DVT BC |  |  |  | 1 | 2 | 1 | 2 | 1 | 2 | Mylar+Sponge(HT800) | Purchase | 德竹 |  |
|  | 3 |  | B47.0112N.0001 | B47.0112N.0001 | B47.0112N.0001 | SPONGE INNER FONRT FAN CAGE DVT BC | new_spong_fg_2mm_re |  |  | 1 | 2 | 1 | 2 | 1 | 2 | Mylar+Sponge(HT800) | Purchase | 德竹 |  |
| MP新增料 | 3 |  |  |  | B47.01132.0001 | MYLAR FAN CAGE LED HOLE BLOCK |  |  |  | 1 | 2 | 0 | 0 | 1 | 2 | Mylar | Purchase | 德竹 |  |
|  | 3 |  | B34.0110V.0001 | B34.0110V.0001 | B34.0110V.0001 | SPG FAN CAGE L DVT BC | NEW_SP_FAN_CAGE_L |  |  | 1 | 2 | 1 | 2 | 1 | 2 |  | Purchase | 華志 |  |
|  | 3 |  | B34.0110W.0001 | B34.0110W.0001 | B34.0110W.0001 | SPG FAN CAGE R DVT BC | NEW_SP_FAN_CAGE_R |  |  | 1 | 2 | 1 | 2 | 1 | 2 |  | Purchase | 華志 |  |
|  | 3 |  | 086.000JD.0548 | 086.000JD.0548 | 086.000JD.0548 | SCRW WAFER M3 L8 NI NYLOK | SCREW |  |  | 2 | 4 | 2 | 4 | 2 | 4 | Screw | Purchase | 文豪 | uses:  2  for handle to cage |
|  | 1 | B34.0110P.0001 | B34.0110P.0001 | B34.0110P.0001 | B60.01112.0001 | ASSY FDPB SUPPORT BKT BRCA | ASSY FDPB SUPPORT BKT  TRITON |  |  | 4 | 4 | 4 | 4 | 4 | 4 | Assy | Assy |  |  |
|  | 2 | TBD | TBD | TBD | B34.0110P.0001 | FDPB SUPPORT BKT BRCA | FDPB SUPPORT BKT  TRITON |  |  | 1 | 4 | 1 | 4 | 1 | 4 | Assy | Assy |  |  |
|  | 3 |  |  |  |  |  | FDPB SUPPORT BKT  TRITON |  | PVT new tool | 1 | 4 | 1 | 4 | 1 | 4 | SGCC(T=0.8mm)/NA | Metal | 長江 | M23 |
|  | 3 |  |  |  |  |  | STD_FDPB_SUPPORT_BKT_BSO-M3-6-Z |  |  | 1 | 4 | 1 | 4 | 1 | 4 | Standoff | Purchase | 長江 |  |
|  | 3 |  |  |  |  |  | SO-FDPB_SUPPORT_BKT |  |  | 2 | 8 | 2 | 8 | 2 | 8 | Standoff | Purchase | 長江 |  |
|  | 2 | B40.0110I.0001 | B40.0110I.0001 | B40.0110I.0001 | B40.0110I.0001 | MYLAR FDPB SUPPORT BKT BRCA | MYLAR FDPB SUPPORT BKT TRITON |  |  | 1 | 4 | 1 | 4 | 1 | 4 | Mylar | Purchase | 德竹 |  |
|  | 1 | B42.0110Z.0001 | B42.0110Z.0001 | B42.0110Z.0001 | B42.0110Z.1001 | CVR DPB SUPPORT AIR DUCT BRCA | FR_DPB_SUPPORT_AIR_DUCT  TRITON |  |  | 2 | 2 | 2 | 2 | 2 | 2 | ASSY | Assy | 信柏 |  |
|  | 2 |  |  |  |  |  | FR_DPB_SUPPORT_AIR_DUCT  TRITON |  | PVT new tool | 1 | 2 | 1 | 2 | 1 | 2 | PC+ABS/NA | Plastic | 信柏 | P10 |
|  | 2 |  |  |  |  |  | INSERT_NUT M3X0.5_L4 |  |  | 8 | 16 | 8 | 16 | 8 | 16 | INSERT NUT | Purchase | 信柏 |  |
|  | 1 |  | B42.0111O.0001 | B42.0111O.0001 | B60.01111.0001 | ASSY DPB BAFFLE BRCA |  |  | PVT new tool | 1 | 1 | 1 | 1 | 1 | 1 | PC+ABS/NA Color:Black | Plastic | 信柏 | P12 |
|  | 2 |  |  |  | B42.0111O.0001 | CVR DPB BAFFLE DVT BRCA |  |  |  | 1 | 1 | 1 | 1 | 1 | 1 |  |  | 信柏 |  |
|  | 2 |  | B47.0112W.0001 | B47.0112W.0001 | B47.0112W.0001 | SPONGE DPB AIR BAFFLE-1 BRCA | SPONGE DPB AIR BAFFLE-1 |  |  | 2 | 2 | 2 | 2 | 2 | 2 | Sponge(YU356) | Purchase | 德竹 |  |
|  | 2 |  | B47.0112X.0001 | B47.0112X.0001 | B47.0112X.0001 | SPONGE DPB AIR BAFFLE-2 BRCA | SPONGE DPB AIR BAFFLE-2 |  |  | 1 | 1 | 1 | 1 | 1 | 1 | Sponge(YU356) | Purchase | 德竹 |  |
|  | 2 |  | B47.0112Y.0001 | B47.0112Y.0001 | B47.0112Y.0001 | SPONGE DPB AIR BAFFLE-3 BRCA | SPONGE DPB AIR BAFFLE-3 |  |  | 1 | 1 | 1 | 1 | 1 | 1 | Sponge(YU356) | Purchase | 德竹 |  |
|  | 1 |  | B33.01115.0001 | B33.01115.0001 | B33.01115.1001 | BRKT FRONT PANEL MINISAS HD BRCA | FRONT PANEL SAS HD BRACKET |  | PVT new tool | 1 | 1 | 0 | 0 | 0 | 0 | SGCC(T=1.0mm)/NA | Metal | 長江 | M28 |
